FILE_TYPE=LIBRARY_PARTS;
primitive 'MOSFETN_1D3S','MOSFETN_1D3S_SM','MOSFETN_1D3S_SMLF';
  pin
    'S1':
      PIN_NUMBER='(1)';
      PINUSE='UNSPEC';
      NO_LOAD_CHECK='BOTH';
      NO_IO_CHECK='BOTH';
      ALLOW_CONNECT='TRUE';
    'S2':
      PIN_NUMBER='(2)';
      PINUSE='UNSPEC';
      NO_LOAD_CHECK='BOTH';
      NO_IO_CHECK='BOTH';
      ALLOW_CONNECT='TRUE';
    'S3':
      PIN_NUMBER='(3)';
      PINUSE='UNSPEC';
      NO_LOAD_CHECK='BOTH';
      NO_IO_CHECK='BOTH';
      ALLOW_CONNECT='TRUE';
    'D':
      PIN_NUMBER='(9)';
      PINUSE='UNSPEC';
      NO_LOAD_CHECK='BOTH';
      NO_IO_CHECK='BOTH';
      ALLOW_CONNECT='TRUE';
    'G':
      PIN_NUMBER='(4)';
      INPUT_LOAD='(-0.01,0.01)';
  end_pin;
  body
    CLASS='IC';
    PART_NAME='MOSFETN_1D3S';
    NC_PINS='(5,6,7,8)';
    PHYS_DES_PREFIX='EU';
  end_body;
end_primitive;
primitive 'MOSFETN_1D3S_SO5LF','MOSFETN_1D3S_SM5LF','MOSFETN_1D3S_SM5','MOSFETN_1D3S_SO8','MOSFETN_1D3S_SM2F','MOSFETN_1D3S_SO5','MOSFETN_1D3S_SOT5';
  pin
    'S1':
      PIN_NUMBER='(1)';
      PINUSE='UNSPEC';
      NO_LOAD_CHECK='BOTH';
      NO_IO_CHECK='BOTH';
      ALLOW_CONNECT='TRUE';
    'S2':
      PIN_NUMBER='(2)';
      PINUSE='UNSPEC';
      NO_LOAD_CHECK='BOTH';
      NO_IO_CHECK='BOTH';
      ALLOW_CONNECT='TRUE';
    'S3':
      PIN_NUMBER='(3)';
      PINUSE='UNSPEC';
      NO_LOAD_CHECK='BOTH';
      NO_IO_CHECK='BOTH';
      ALLOW_CONNECT='TRUE';
    'D':
      PIN_NUMBER='(5)';
      PINUSE='UNSPEC';
      NO_LOAD_CHECK='BOTH';
      NO_IO_CHECK='BOTH';
      ALLOW_CONNECT='TRUE';
    'G':
      PIN_NUMBER='(4)';
      INPUT_LOAD='(-0.01,0.01)';
  end_pin;
  body
    PART_NAME='MOSFETN_1D3S';
    PHYS_DES_PREFIX='EU';
  end_body;
end_primitive;
primitive 'MOSFETN_1D3S_MLF5';
  pin
    'S1':
      PIN_NUMBER='(1)';
      PINUSE='UNSPEC';
      NO_LOAD_CHECK='BOTH';
      NO_IO_CHECK='BOTH';
      ALLOW_CONNECT='TRUE';
    'S2':
      PIN_NUMBER='(2)';
      PINUSE='UNSPEC';
      NO_LOAD_CHECK='BOTH';
      NO_IO_CHECK='BOTH';
      ALLOW_CONNECT='TRUE';
    'S3':
      PIN_NUMBER='(3)';
      PINUSE='UNSPEC';
      NO_LOAD_CHECK='BOTH';
      NO_IO_CHECK='BOTH';
      ALLOW_CONNECT='TRUE';
    'D':
      PIN_NUMBER='(5)';
      PINUSE='UNSPEC';
      NO_LOAD_CHECK='BOTH';
      NO_IO_CHECK='BOTH';
      ALLOW_CONNECT='TRUE';
    'G':
      PIN_NUMBER='(4)';
      INPUT_LOAD='(-0.01,0.01)';
  end_pin;
  body
    PART_NAME='MOSFETN_1D3S';
    PHYS_DES_PREFIX='EU';
  end_body;
end_primitive;
END.
